# BASEBOARD_FAB2 (Tioga Pass) — schematic netlist excerpt (pin names and nets, part order shuffled) for the footprints in the layout excerpt that follows; sources: Cadence DE-HDL packaged netlist, KiCad conversion of Wiwynn_Tioga_Pass_MB.brd

C25W60  CAP  1.0UF 16V 10% X6S  pkg 0402  page 149 : A = P3V3_STBY ; B = GND
R32W4  RES  49.9K 1% CHIP  pkg 0402  page 185 : A = P1V8_M2 ; B = GND
R1U63  RES  1.00K 1% CHIP  pkg 0402  page 137 : A = PD_RST_RTCRST_N ; B = GND

(kicad_pcb
	(version 20260206)
	(generator "pcbnew")
	(generator_version "10.0")
	(general
		(thickness 1.6)
		(legacy_teardrops no)
	)
	(paper "A4")
	(title_block
		(title "Wiwynn_Tioga_Pass_MB.brd")
		(comment 1 "Tioga Pass / footprints 4454-4456 of 4770")
	)
	(layers
		(0 "F.Cu" signal "TOP")
		(4 "In1.Cu" signal "L2GND")
		(6 "In2.Cu" signal "L3")
		(8 "In3.Cu" signal "L4GND")
		(10 "In4.Cu" signal "L5")
		(12 "In5.Cu" signal "L6GND")
		(14 "In6.Cu" signal "L7VCC")
		(16 "In7.Cu" signal "L8VCC")
		(18 "In8.Cu" signal "L9GND")
		(20 "In9.Cu" signal "L10")
		(22 "In10.Cu" signal "L11GND")
		(24 "In11.Cu" signal "L12")
		(26 "In12.Cu" signal "L13GND")
		(2 "B.Cu" signal "BOTTOM")
		(9 "F.Adhes" user "F.Adhesive")
		(11 "B.Adhes" user "B.Adhesive")
		(13 "F.Paste" user "Package Geometry/Pastemask Top")
		(15 "B.Paste" user "Package Geometry/Pastemask Bottom")
		(5 "F.SilkS" user "Ref Des/Silkscreen Top")
		(7 "B.SilkS" user "Ref Des/Silkscreen Bottom")
		(1 "F.Mask" user "Board Geometry/Soldermask Top")
		(3 "B.Mask" user "Board Geometry/Soldermask Bottom")
		(17 "Dwgs.User" user "User.Drawings")
		(19 "Cmts.User" user "User.Comments")
		(21 "Eco1.User" user "User.Eco1")
		(23 "Eco2.User" user "User.Eco2")
		(25 "Edge.Cuts" user "Board Geometry/Outline")
		(27 "Margin" user)
		(31 "F.CrtYd" user "Package Geometry/Place Bound Top")
		(29 "B.CrtYd" user "Package Geometry/Place Bound Bottom")
		(35 "F.Fab" user "Ref Des/Assembly Top")
		(33 "B.Fab" user "Ref Des/Assembly Bottom")
	)
	(footprint ""
		(layer "B.Cu")
		(at 394.2207 -19.812 90)
		(property "Reference" "R32W4"
			(at 0.8382 -0.67818 90)
			(unlocked yes)
			(layer "B.SilkS")
			(effects
				(font
					(size 0.4064 0.254)
					(thickness 0.1524)
				)
				(justify left mirror)
			)
		)
		(property "Value" ""
			(at 0 0 90)
			(layer "B.Fab")
			(effects
				(font
					(size 1.27 1.27)
				)
				(justify mirror)
			)
		)
		(duplicate_pad_numbers_are_jumpers no)
		(fp_poly
			(pts
				(xy 0.2794 -0.1016) (xy -0.2794 -0.1016) (xy -0.2794 0.9906) (xy 0.2794 0.9906)
			)
			(stroke
				(width 0)
				(type default)
			)
			(fill no)
			(layer "B.CrtYd")
		)
		(fp_line
			(start 0.2794 -0.1016)
			(end 0.2794 0.9906)
			(stroke
				(width 0.1)
				(type default)
			)
			(layer "B.Fab")
		)
		(fp_line
			(start -0.2794 -0.1016)
			(end 0.2794 -0.1016)
			(stroke
				(width 0.1)
				(type default)
			)
			(layer "B.Fab")
		)
		(fp_line
			(start 0.2794 0.9906)
			(end -0.2794 0.9906)
			(stroke
				(width 0.1)
				(type default)
			)
			(layer "B.Fab")
		)
		(fp_line
			(start -0.2794 0.9906)
			(end -0.2794 -0.1016)
			(stroke
				(width 0.1)
				(type default)
			)
			(layer "B.Fab")
		)
		(pad "1" smd rect
			(at 0 0 270)
			(size 0.508 0.508)
			(layers "B.Cu" "B.Mask" "B.Paste")
			(net "P1V8_M2")
		)
		(pad "2" smd rect
			(at 0 0.889 270)
			(size 0.508 0.508)
			(layers "B.Cu" "B.Mask" "B.Paste")
			(net "GND")
		)
		(zone
			(layer "B.Cu")
			(hatch none 0.5)
			(connect_pads
				(clearance 0)
			)
			(min_thickness 0.25)
			(keepout
				(tracks allowed)
				(vias not_allowed)
				(pads allowed)
				(copperpour not_allowed)
				(footprints allowed)
			)
			(placement
				(enabled no)
				(sheetname "")
			)
			(fill
				(thermal_gap 0.5)
				(thermal_bridge_width 0.5)
				(island_removal_mode 0)
			)
			(polygon
				(pts
					(xy 394.4747 -20.066) (xy 394.4747 -19.558) (xy 394.8557 -19.558) (xy 394.8557 -20.066)
				)
			)
		)
		(zone
			(layer "B.Cu")
			(hatch none 0.5)
			(connect_pads
				(clearance 0)
			)
			(min_thickness 0.25)
			(keepout
				(tracks not_allowed)
				(vias allowed)
				(pads allowed)
				(copperpour not_allowed)
				(footprints allowed)
			)
			(placement
				(enabled no)
				(sheetname "")
			)
			(fill
				(thermal_gap 0.5)
				(thermal_bridge_width 0.5)
				(island_removal_mode 0)
			)
			(polygon
				(pts
					(xy 394.8557 -20.066) (xy 394.8557 -19.558) (xy 394.4747 -19.558) (xy 394.4747 -20.066)
				)
			)
		)
	)
	(footprint ""
		(layer "B.Cu")
		(at 409.3845 -24.384 -90)
		(property "Reference" "C25W60"
			(at 0.8382 -0.67818 270)
			(unlocked yes)
			(layer "B.SilkS")
			(effects
				(font
					(size 0.4064 0.254)
					(thickness 0.1524)
				)
				(justify left mirror)
			)
		)
		(property "Value" ""
			(at 0 0 90)
			(layer "B.Fab")
			(effects
				(font
					(size 1.27 1.27)
				)
				(justify mirror)
			)
		)
		(duplicate_pad_numbers_are_jumpers no)
		(fp_poly
			(pts
				(xy -0.3048 -0.1016) (xy -0.3048 0.9906) (xy 0.3048 0.9906) (xy 0.3048 -0.1016)
			)
			(stroke
				(width 0)
				(type default)
			)
			(fill no)
			(layer "B.CrtYd")
		)
		(fp_line
			(start -0.3048 0.9906)
			(end -0.3048 -0.1016)
			(stroke
				(width 0.1)
				(type default)
			)
			(layer "B.Fab")
		)
		(fp_line
			(start 0.3048 0.9906)
			(end -0.3048 0.9906)
			(stroke
				(width 0.1)
				(type default)
			)
			(layer "B.Fab")
		)
		(fp_line
			(start -0.3048 -0.1016)
			(end 0.3048 -0.1016)
			(stroke
				(width 0.1)
				(type default)
			)
			(layer "B.Fab")
		)
		(fp_line
			(start 0.3048 -0.1016)
			(end 0.3048 0.9906)
			(stroke
				(width 0.1)
				(type default)
			)
			(layer "B.Fab")
		)
		(pad "1" smd rect
			(at 0 0 90)
			(size 0.508 0.508)
			(layers "B.Cu" "B.Mask" "B.Paste")
			(net "P3V3_STBY")
		)
		(pad "2" smd rect
			(at 0 0.889 90)
			(size 0.508 0.508)
			(layers "B.Cu" "B.Mask" "B.Paste")
			(net "GND")
		)
		(zone
			(layer "B.Cu")
			(hatch none 0.5)
			(connect_pads
				(clearance 0)
			)
			(min_thickness 0.25)
			(keepout
				(tracks not_allowed)
				(vias allowed)
				(pads allowed)
				(copperpour not_allowed)
				(footprints allowed)
			)
			(placement
				(enabled no)
				(sheetname "")
			)
			(fill
				(thermal_gap 0.5)
				(thermal_bridge_width 0.5)
				(island_removal_mode 0)
			)
			(polygon
				(pts
					(xy 408.7495 -24.13) (xy 408.7495 -24.638) (xy 409.1305 -24.638) (xy 409.1305 -24.13)
				)
			)
		)
		(zone
			(layer "B.Cu")
			(hatch none 0.5)
			(connect_pads
				(clearance 0)
			)
			(min_thickness 0.25)
			(keepout
				(tracks allowed)
				(vias not_allowed)
				(pads allowed)
				(copperpour not_allowed)
				(footprints allowed)
			)
			(placement
				(enabled no)
				(sheetname "")
			)
			(fill
				(thermal_gap 0.5)
				(thermal_bridge_width 0.5)
				(island_removal_mode 0)
			)
			(polygon
				(pts
					(xy 409.1305 -24.13) (xy 409.1305 -24.638) (xy 408.7495 -24.638) (xy 408.7495 -24.13)
				)
			)
		)
	)
	(footprint ""
		(layer "B.Cu")
		(at 452.35241 -3.852672 90)
		(property "Reference" "R1U63"
			(at 0 0 90)
			(layer "B.SilkS")
			(hide yes)
			(effects
				(font
					(size 1.27 1.27)
				)
				(justify mirror)
			)
		)
		(property "Value" ""
			(at 0 0 90)
			(layer "B.Fab")
			(effects
				(font
					(size 1.27 1.27)
				)
				(justify mirror)
			)
		)
		(duplicate_pad_numbers_are_jumpers no)
		(fp_poly
			(pts
				(xy 0.2794 -0.1016) (xy -0.2794 -0.1016) (xy -0.2794 0.9906) (xy 0.2794 0.9906)
			)
			(stroke
				(width 0)
				(type default)
			)
			(fill no)
			(layer "B.CrtYd")
		)
		(fp_line
			(start 0.2794 -0.1016)
			(end 0.2794 0.9906)
			(stroke
				(width 0.1)
				(type default)
			)
			(layer "B.Fab")
		)
		(fp_line
			(start -0.2794 -0.1016)
			(end 0.2794 -0.1016)
			(stroke
				(width 0.1)
				(type default)
			)
			(layer "B.Fab")
		)
		(fp_line
			(start 0.2794 0.9906)
			(end -0.2794 0.9906)
			(stroke
				(width 0.1)
				(type default)
			)
			(layer "B.Fab")
		)
		(fp_line
			(start -0.2794 0.9906)
			(end -0.2794 -0.1016)
			(stroke
				(width 0.1)
				(type default)
			)
			(layer "B.Fab")
		)
		(pad "1" smd rect
			(at 0 0 270)
			(size 0.508 0.508)
			(layers "B.Cu" "B.Mask" "B.Paste")
			(net "PD_RST_RTCRST_N")
		)
		(pad "2" smd rect
			(at 0 0.889 270)
			(size 0.508 0.508)
			(layers "B.Cu" "B.Mask" "B.Paste")
			(net "GND")
		)
		(zone
			(layer "B.Cu")
			(hatch none 0.5)
			(connect_pads
				(clearance 0)
			)
			(min_thickness 0.25)
			(keepout
				(tracks allowed)
				(vias not_allowed)
				(pads allowed)
				(copperpour not_allowed)
				(footprints allowed)
			)
			(placement
				(enabled no)
				(sheetname "")
			)
			(fill
				(thermal_gap 0.5)
				(thermal_bridge_width 0.5)
				(island_removal_mode 0)
			)
			(polygon
				(pts
					(xy 452.60641 -4.106672) (xy 452.60641 -3.598672) (xy 452.98741 -3.598672) (xy 452.98741 -4.106672)
				)
			)
		)
		(zone
			(layer "B.Cu")
			(hatch none 0.5)
			(connect_pads
				(clearance 0)
			)
			(min_thickness 0.25)
			(keepout
				(tracks not_allowed)
				(vias allowed)
				(pads allowed)
				(copperpour not_allowed)
				(footprints allowed)
			)
			(placement
				(enabled no)
				(sheetname "")
			)
			(fill
				(thermal_gap 0.5)
				(thermal_bridge_width 0.5)
				(island_removal_mode 0)
			)
			(polygon
				(pts
					(xy 452.98741 -4.106672) (xy 452.98741 -3.598672) (xy 452.60641 -3.598672) (xy 452.60641 -4.106672)
				)
			)
		)
	)
)
